(kicad_pcb
	(version 20260206)
	(generator "pcbnew")
	(generator_version "10.0")
	(general
		(thickness 1.6)
		(legacy_teardrops no)
	)
	(paper "A4")
	(title_block
		(title "peb — Lightning_PEB_BRD.brd")
		(comment 1 "Lightning (Wiwynn / Facebook NVMe JBOF) / footprints 1230-1236 of 2563")
	)
	(layers
		(0 "F.Cu" signal "TOP")
		(4 "In1.Cu" signal "L2GND")
		(6 "In2.Cu" signal "L3")
		(8 "In3.Cu" signal "L4VCC")
		(10 "In4.Cu" signal "L5VCC")
		(12 "In5.Cu" signal "L6")
		(14 "In6.Cu" signal "L7GND")
		(2 "B.Cu" signal "BOTTOM")
		(9 "F.Adhes" user "F.Adhesive")
		(11 "B.Adhes" user "B.Adhesive")
		(13 "F.Paste" user "Package Geometry/Pastemask Top")
		(15 "B.Paste" user "Package Geometry/Pastemask Bottom")
		(5 "F.SilkS" user "Ref Des/Silkscreen Top")
		(7 "B.SilkS" user "Ref Des/Silkscreen Bottom")
		(1 "F.Mask" user "Board Geometry/Soldermask Top")
		(3 "B.Mask" user "Board Geometry/Soldermask Bottom")
		(17 "Dwgs.User" user "User.Drawings")
		(19 "Cmts.User" user "User.Comments")
		(21 "Eco1.User" user "User.Eco1")
		(23 "Eco2.User" user "User.Eco2")
		(25 "Edge.Cuts" user "Board Geometry/Outline")
		(27 "Margin" user)
		(31 "F.CrtYd" user "Package Geometry/Place Bound Top")
		(29 "B.CrtYd" user "Package Geometry/Place Bound Bottom")
		(35 "F.Fab" user "Ref Des/Assembly Top")
		(33 "B.Fab" user "Ref Des/Assembly Bottom")
	)
	(footprint ""
		(layer "F.Cu")
		(at 49.657 -150.495)
		(property "Reference" "R165"
			(at 0 0 0)
			(layer "F.SilkS")
			(hide yes)
			(effects
				(font
					(size 1.27 1.27)
				)
			)
		)
		(property "Value" "4K7R2F-GP"
			(at 0.064008 -3.993896 0)
			(unlocked yes)
			(layer "F.Fab")
			(hide yes)
			(effects
				(font
					(size 1.016 1.016)
					(thickness 0.1524)
				)
			)
		)
		(property "Device Type" "R402H16"
			(at 0.064008 -5.517896 0)
			(unlocked yes)
			(layer "F.Fab")
			(hide yes)
			(effects
				(font
					(size 1.016 1.016)
					(thickness 0.1524)
				)
			)
		)
		(duplicate_pad_numbers_are_jumpers no)
		(fp_line
			(start -0.508 -0.9398)
			(end -0.508 0.9398)
			(stroke
				(width 0.1524)
				(type default)
			)
			(layer "F.SilkS")
		)
		(fp_line
			(start 0.508 -0.9398)
			(end -0.508 -0.9398)
			(stroke
				(width 0.1524)
				(type default)
			)
			(layer "F.SilkS")
		)
		(fp_rect
			(start -0.508 0.9398)
			(end 0.508 -0.9398)
			(stroke
				(width 0)
				(type default)
			)
			(fill no)
			(layer "F.CrtYd")
		)
		(fp_rect
			(start -0.508 0.9398)
			(end 0.508 -0.9398)
			(stroke
				(width 0)
				(type default)
			)
			(fill no)
			(layer "F.Fab")
		)
		(pad "1" smd custom
			(at 0 -0.4445)
			(size 0.1397 0.1397)
			(layers "F.Cu" "F.Mask" "F.Paste")
			(net "TEMP_2_A1")
			(options
				(clearance outline)
				(anchor circle)
			)
			(primitives
				(gr_poly
					(pts
						(arc
							(start -0.1778 -0.2794)
							(mid -0.249642 -0.249642)
							(end -0.2794 -0.1778)
						)
						(arc
							(start -0.2794 0.1778)
							(mid -0.249642 0.249642)
							(end -0.1778 0.2794)
						)
						(arc
							(start 0.1778 0.2794)
							(mid 0.249642 0.249642)
							(end 0.2794 0.1778)
						)
						(arc
							(start 0.2794 -0.1778)
							(mid 0.249642 -0.249642)
							(end 0.1778 -0.2794)
						)
					)
					(width 0)
					(fill yes)
				)
			)
		)
		(pad "2" smd custom
			(at 0 0.4445)
			(size 0.1397 0.1397)
			(layers "F.Cu" "F.Mask" "F.Paste")
			(net "GND")
			(options
				(clearance outline)
				(anchor circle)
			)
			(primitives
				(gr_poly
					(pts
						(arc
							(start -0.1778 -0.2794)
							(mid -0.249642 -0.249642)
							(end -0.2794 -0.1778)
						)
						(arc
							(start -0.2794 0.1778)
							(mid -0.249642 0.249642)
							(end -0.1778 0.2794)
						)
						(arc
							(start 0.1778 0.2794)
							(mid 0.249642 0.249642)
							(end 0.2794 0.1778)
						)
						(arc
							(start 0.2794 -0.1778)
							(mid 0.249642 -0.249642)
							(end 0.1778 -0.2794)
						)
					)
					(width 0)
					(fill yes)
				)
			)
		)
	)
	(footprint ""
		(layer "F.Cu")
		(at 75.180952 -146.85391 90)
		(property "Reference" "R197"
			(at 0 0 90)
			(layer "F.SilkS")
			(hide yes)
			(effects
				(font
					(size 1.27 1.27)
				)
			)
		)
		(property "Value" "8K2R2J-3-GP"
			(at 0.064008 -3.993896 90)
			(unlocked yes)
			(layer "F.Fab")
			(hide yes)
			(effects
				(font
					(size 1.016 1.016)
					(thickness 0.1524)
				)
			)
		)
		(property "Device Type" "R402H16"
			(at 0.064008 -5.517896 90)
			(unlocked yes)
			(layer "F.Fab")
			(hide yes)
			(effects
				(font
					(size 1.016 1.016)
					(thickness 0.1524)
				)
			)
		)
		(duplicate_pad_numbers_are_jumpers no)
		(fp_line
			(start 0.508 -0.9398)
			(end -0.508 -0.9398)
			(stroke
				(width 0.1524)
				(type default)
			)
			(layer "F.SilkS")
		)
		(fp_line
			(start -0.508 -0.9398)
			(end -0.508 0.9398)
			(stroke
				(width 0.1524)
				(type default)
			)
			(layer "F.SilkS")
		)
		(fp_rect
			(start -0.508 0.9398)
			(end 0.508 -0.9398)
			(stroke
				(width 0)
				(type default)
			)
			(fill no)
			(layer "F.CrtYd")
		)
		(fp_rect
			(start -0.508 0.9398)
			(end 0.508 -0.9398)
			(stroke
				(width 0)
				(type default)
			)
			(fill no)
			(layer "F.Fab")
		)
		(pad "1" smd custom
			(at 0 -0.4445 90)
			(size 0.1397 0.1397)
			(layers "F.Cu" "F.Mask" "F.Paste")
			(net "EEPROM_A0_R")
			(options
				(clearance outline)
				(anchor circle)
			)
			(primitives
				(gr_poly
					(pts
						(arc
							(start -0.1778 -0.2794)
							(mid -0.249642 -0.249642)
							(end -0.2794 -0.1778)
						)
						(arc
							(start -0.2794 0.1778)
							(mid -0.249642 0.249642)
							(end -0.1778 0.2794)
						)
						(arc
							(start 0.1778 0.2794)
							(mid 0.249642 0.249642)
							(end 0.2794 0.1778)
						)
						(arc
							(start 0.2794 -0.1778)
							(mid 0.249642 -0.249642)
							(end 0.1778 -0.2794)
						)
					)
					(width 0)
					(fill yes)
				)
			)
		)
		(pad "2" smd custom
			(at 0 0.4445 90)
			(size 0.1397 0.1397)
			(layers "F.Cu" "F.Mask" "F.Paste")
			(net "GND")
			(options
				(clearance outline)
				(anchor circle)
			)
			(primitives
				(gr_poly
					(pts
						(arc
							(start -0.1778 -0.2794)
							(mid -0.249642 -0.249642)
							(end -0.2794 -0.1778)
						)
						(arc
							(start -0.2794 0.1778)
							(mid -0.249642 0.249642)
							(end -0.1778 0.2794)
						)
						(arc
							(start 0.1778 0.2794)
							(mid 0.249642 0.249642)
							(end 0.2794 0.1778)
						)
						(arc
							(start 0.2794 -0.1778)
							(mid 0.249642 -0.249642)
							(end 0.1778 -0.2794)
						)
					)
					(width 0)
					(fill yes)
				)
			)
		)
	)
	(footprint ""
		(layer "F.Cu")
		(at 298.792138 -212.420454 180)
		(property "Reference" "C76"
			(at 0 0 180)
			(layer "F.SilkS")
			(hide yes)
			(effects
				(font
					(size 1.27 1.27)
				)
			)
		)
		(property "Value" "SCD22U10V2KX-1GP"
			(at 1.1811 -2.7051 180)
			(unlocked yes)
			(layer "F.Fab")
			(hide yes)
			(effects
				(font
					(size 1.016 1.016)
					(thickness 0.1524)
				)
			)
		)
		(property "Device Type" "C402H22"
			(at 1.1811 -4.2291 180)
			(unlocked yes)
			(layer "F.Fab")
			(hide yes)
			(effects
				(font
					(size 1.016 1.016)
					(thickness 0.1524)
				)
			)
		)
		(duplicate_pad_numbers_are_jumpers no)
		(fp_rect
			(start -0.4318 0.9525)
			(end 0.4318 -0.9525)
			(stroke
				(width 0)
				(type default)
			)
			(fill no)
			(layer "F.CrtYd")
		)
		(fp_rect
			(start -0.4318 0.9525)
			(end 0.4318 -0.9525)
			(stroke
				(width 0)
				(type default)
			)
			(fill no)
			(layer "F.Fab")
		)
		(pad "1" smd custom
			(at 0 -0.4445 180)
			(size 0.1524 0.1524)
			(layers "F.Cu" "F.Mask" "F.Paste")
			(net "PCIE_TX_CAP_P27")
			(options
				(clearance outline)
				(anchor circle)
			)
			(primitives
				(gr_poly
					(pts
						(arc
							(start 0.3048 -0.2032)
							(mid 0.275042 -0.275042)
							(end 0.2032 -0.3048)
						)
						(arc
							(start -0.2032 -0.3048)
							(mid -0.275042 -0.275042)
							(end -0.3048 -0.2032)
						)
						(arc
							(start -0.3048 0.2032)
							(mid -0.275042 0.275042)
							(end -0.2032 0.3048)
						)
						(arc
							(start 0.2032 0.3048)
							(mid 0.275042 0.275042)
							(end 0.3048 0.2032)
						)
					)
					(width 0)
					(fill yes)
				)
			)
		)
		(pad "2" smd custom
			(at 0 0.4445 180)
			(size 0.1524 0.1524)
			(layers "F.Cu" "F.Mask" "F.Paste")
			(net "PCIE_TX_P27")
			(options
				(clearance outline)
				(anchor circle)
			)
			(primitives
				(gr_poly
					(pts
						(arc
							(start 0.3048 -0.2032)
							(mid 0.275042 -0.275042)
							(end 0.2032 -0.3048)
						)
						(arc
							(start -0.2032 -0.3048)
							(mid -0.275042 -0.275042)
							(end -0.3048 -0.2032)
						)
						(arc
							(start -0.3048 0.2032)
							(mid -0.275042 0.275042)
							(end -0.2032 0.3048)
						)
						(arc
							(start 0.2032 0.3048)
							(mid 0.275042 0.275042)
							(end 0.3048 0.2032)
						)
					)
					(width 0)
					(fill yes)
				)
			)
		)
	)
	(footprint ""
		(layer "F.Cu")
		(at 20.864576 -129.243074 90)
		(property "Reference" "R352"
			(at 0 0 90)
			(layer "F.SilkS")
			(hide yes)
			(effects
				(font
					(size 1.27 1.27)
				)
			)
		)
		(property "Value" "3K3R2F-2-GP"
			(at 0.064008 -3.993896 90)
			(unlocked yes)
			(layer "F.Fab")
			(hide yes)
			(effects
				(font
					(size 1.016 1.016)
					(thickness 0.1524)
				)
			)
		)
		(property "Device Type" "R402H16"
			(at 0.064008 -5.517896 90)
			(unlocked yes)
			(layer "F.Fab")
			(hide yes)
			(effects
				(font
					(size 1.016 1.016)
					(thickness 0.1524)
				)
			)
		)
		(duplicate_pad_numbers_are_jumpers no)
		(fp_line
			(start 0.508 -0.9398)
			(end -0.508 -0.9398)
			(stroke
				(width 0.1524)
				(type default)
			)
			(layer "F.SilkS")
		)
		(fp_line
			(start -0.508 -0.9398)
			(end -0.508 0.9398)
			(stroke
				(width 0.1524)
				(type default)
			)
			(layer "F.SilkS")
		)
		(fp_rect
			(start -0.508 0.9398)
			(end 0.508 -0.9398)
			(stroke
				(width 0)
				(type default)
			)
			(fill no)
			(layer "F.CrtYd")
		)
		(fp_rect
			(start -0.508 0.9398)
			(end 0.508 -0.9398)
			(stroke
				(width 0)
				(type default)
			)
			(fill no)
			(layer "F.Fab")
		)
		(pad "1" smd custom
			(at 0 -0.4445 90)
			(size 0.1397 0.1397)
			(layers "F.Cu" "F.Mask" "F.Paste")
			(net "P3V3_STBY")
			(options
				(clearance outline)
				(anchor circle)
			)
			(primitives
				(gr_poly
					(pts
						(arc
							(start -0.1778 -0.2794)
							(mid -0.249642 -0.249642)
							(end -0.2794 -0.1778)
						)
						(arc
							(start -0.2794 0.1778)
							(mid -0.249642 0.249642)
							(end -0.1778 0.2794)
						)
						(arc
							(start 0.1778 0.2794)
							(mid 0.249642 0.249642)
							(end 0.2794 0.1778)
						)
						(arc
							(start 0.2794 -0.1778)
							(mid 0.249642 -0.249642)
							(end 0.1778 -0.2794)
						)
					)
					(width 0)
					(fill yes)
				)
			)
		)
		(pad "2" smd custom
			(at 0 0.4445 90)
			(size 0.1397 0.1397)
			(layers "F.Cu" "F.Mask" "F.Paste")
			(net "ROMA11")
			(options
				(clearance outline)
				(anchor circle)
			)
			(primitives
				(gr_poly
					(pts
						(arc
							(start -0.1778 -0.2794)
							(mid -0.249642 -0.249642)
							(end -0.2794 -0.1778)
						)
						(arc
							(start -0.2794 0.1778)
							(mid -0.249642 0.249642)
							(end -0.1778 0.2794)
						)
						(arc
							(start 0.1778 0.2794)
							(mid 0.249642 0.249642)
							(end 0.2794 0.1778)
						)
						(arc
							(start 0.2794 -0.1778)
							(mid 0.249642 -0.249642)
							(end 0.1778 -0.2794)
						)
					)
					(width 0)
					(fill yes)
				)
			)
		)
	)
	(footprint ""
		(layer "F.Cu")
		(at 273.992086 -212.420454 180)
		(property "Reference" "C101"
			(at 0 0 180)
			(layer "F.SilkS")
			(hide yes)
			(effects
				(font
					(size 1.27 1.27)
				)
			)
		)
		(property "Value" "SCD22U10V2KX-1GP"
			(at 1.1811 -2.7051 180)
			(unlocked yes)
			(layer "F.Fab")
			(hide yes)
			(effects
				(font
					(size 1.016 1.016)
					(thickness 0.1524)
				)
			)
		)
		(property "Device Type" "C402H22"
			(at 1.1811 -4.2291 180)
			(unlocked yes)
			(layer "F.Fab")
			(hide yes)
			(effects
				(font
					(size 1.016 1.016)
					(thickness 0.1524)
				)
			)
		)
		(duplicate_pad_numbers_are_jumpers no)
		(fp_rect
			(start -0.4318 0.9525)
			(end 0.4318 -0.9525)
			(stroke
				(width 0)
				(type default)
			)
			(fill no)
			(layer "F.CrtYd")
		)
		(fp_rect
			(start -0.4318 0.9525)
			(end 0.4318 -0.9525)
			(stroke
				(width 0)
				(type default)
			)
			(fill no)
			(layer "F.Fab")
		)
		(pad "1" smd custom
			(at 0 -0.4445 180)
			(size 0.1524 0.1524)
			(layers "F.Cu" "F.Mask" "F.Paste")
			(net "PCIE_TX_CAP_P34")
			(options
				(clearance outline)
				(anchor circle)
			)
			(primitives
				(gr_poly
					(pts
						(arc
							(start 0.3048 -0.2032)
							(mid 0.275042 -0.275042)
							(end 0.2032 -0.3048)
						)
						(arc
							(start -0.2032 -0.3048)
							(mid -0.275042 -0.275042)
							(end -0.3048 -0.2032)
						)
						(arc
							(start -0.3048 0.2032)
							(mid -0.275042 0.275042)
							(end -0.2032 0.3048)
						)
						(arc
							(start 0.2032 0.3048)
							(mid 0.275042 0.275042)
							(end 0.3048 0.2032)
						)
					)
					(width 0)
					(fill yes)
				)
			)
		)
		(pad "2" smd custom
			(at 0 0.4445 180)
			(size 0.1524 0.1524)
			(layers "F.Cu" "F.Mask" "F.Paste")
			(net "PCIE_TX_P34")
			(options
				(clearance outline)
				(anchor circle)
			)
			(primitives
				(gr_poly
					(pts
						(arc
							(start 0.3048 -0.2032)
							(mid 0.275042 -0.275042)
							(end 0.2032 -0.3048)
						)
						(arc
							(start -0.2032 -0.3048)
							(mid -0.275042 -0.275042)
							(end -0.3048 -0.2032)
						)
						(arc
							(start -0.3048 0.2032)
							(mid -0.275042 0.275042)
							(end -0.2032 0.3048)
						)
						(arc
							(start 0.2032 0.3048)
							(mid 0.275042 0.275042)
							(end 0.3048 0.2032)
						)
					)
					(width 0)
					(fill yes)
				)
			)
		)
	)
	(footprint ""
		(layer "F.Cu")
		(at 154.1018 -87.4268 -90)
		(property "Reference" "R99"
			(at 0 0 270)
			(layer "F.SilkS")
			(hide yes)
			(effects
				(font
					(size 1.27 1.27)
				)
			)
		)
		(property "Value" "10KR2F-2-GP"
			(at 0.064008 -3.993896 270)
			(unlocked yes)
			(layer "F.Fab")
			(hide yes)
			(effects
				(font
					(size 1.016 1.016)
					(thickness 0.1524)
				)
			)
		)
		(property "Device Type" "R402H16"
			(at 0.064008 -5.517896 270)
			(unlocked yes)
			(layer "F.Fab")
			(hide yes)
			(effects
				(font
					(size 1.016 1.016)
					(thickness 0.1524)
				)
			)
		)
		(duplicate_pad_numbers_are_jumpers no)
		(fp_line
			(start -0.508 -0.9398)
			(end -0.508 0.9398)
			(stroke
				(width 0.1524)
				(type default)
			)
			(layer "F.SilkS")
		)
		(fp_line
			(start 0.508 -0.9398)
			(end -0.508 -0.9398)
			(stroke
				(width 0.1524)
				(type default)
			)
			(layer "F.SilkS")
		)
		(fp_rect
			(start -0.508 0.9398)
			(end 0.508 -0.9398)
			(stroke
				(width 0)
				(type default)
			)
			(fill no)
			(layer "F.CrtYd")
		)
		(fp_rect
			(start -0.508 0.9398)
			(end 0.508 -0.9398)
			(stroke
				(width 0)
				(type default)
			)
			(fill no)
			(layer "F.Fab")
		)
		(pad "1" smd custom
			(at 0 -0.4445 270)
			(size 0.1397 0.1397)
			(layers "F.Cu" "F.Mask" "F.Paste")
			(net "GND")
			(options
				(clearance outline)
				(anchor circle)
			)
			(primitives
				(gr_poly
					(pts
						(arc
							(start -0.1778 -0.2794)
							(mid -0.249642 -0.249642)
							(end -0.2794 -0.1778)
						)
						(arc
							(start -0.2794 0.1778)
							(mid -0.249642 0.249642)
							(end -0.1778 0.2794)
						)
						(arc
							(start 0.1778 0.2794)
							(mid 0.249642 0.249642)
							(end 0.2794 0.1778)
						)
						(arc
							(start 0.2794 -0.1778)
							(mid 0.249642 -0.249642)
							(end 0.1778 -0.2794)
						)
					)
					(width 0)
					(fill yes)
				)
			)
		)
		(pad "2" smd custom
			(at 0 0.4445 270)
			(size 0.1397 0.1397)
			(layers "F.Cu" "F.Mask" "F.Paste")
			(net "CLKGNE_SADR_R")
			(options
				(clearance outline)
				(anchor circle)
			)
			(primitives
				(gr_poly
					(pts
						(arc
							(start -0.1778 -0.2794)
							(mid -0.249642 -0.249642)
							(end -0.2794 -0.1778)
						)
						(arc
							(start -0.2794 0.1778)
							(mid -0.249642 0.249642)
							(end -0.1778 0.2794)
						)
						(arc
							(start 0.1778 0.2794)
							(mid 0.249642 0.249642)
							(end 0.2794 0.1778)
						)
						(arc
							(start 0.2794 -0.1778)
							(mid 0.249642 -0.249642)
							(end 0.1778 -0.2794)
						)
					)
					(width 0)
					(fill yes)
				)
			)
		)
	)
	(footprint ""
		(layer "F.Cu")
		(at 37.211 -200.533)
		(property "Reference" "C695"
			(at 0 0 0)
			(layer "F.SilkS")
			(hide yes)
			(effects
				(font
					(size 1.27 1.27)
				)
			)
		)
		(property "Value" "SCD01U50V2KX-1GP"
			(at 1.1811 -2.7051 0)
			(unlocked yes)
			(layer "F.Fab")
			(hide yes)
			(effects
				(font
					(size 1.016 1.016)
					(thickness 0.1524)
				)
			)
		)
		(property "Device Type" "C402H22"
			(at 1.1811 -4.2291 0)
			(unlocked yes)
			(layer "F.Fab")
			(hide yes)
			(effects
				(font
					(size 1.016 1.016)
					(thickness 0.1524)
				)
			)
		)
		(duplicate_pad_numbers_are_jumpers no)
		(fp_rect
			(start -0.4318 0.9525)
			(end 0.4318 -0.9525)
			(stroke
				(width 0)
				(type default)
			)
			(fill no)
			(layer "F.CrtYd")
		)
		(fp_rect
			(start -0.4318 0.9525)
			(end 0.4318 -0.9525)
			(stroke
				(width 0)
				(type default)
			)
			(fill no)
			(layer "F.Fab")
		)
		(pad "1" smd custom
			(at 0 -0.4445)
			(size 0.1524 0.1524)
			(layers "F.Cu" "F.Mask" "F.Paste")
			(net "P3V3_STBY")
			(options
				(clearance outline)
				(anchor circle)
			)
			(primitives
				(gr_poly
					(pts
						(arc
							(start 0.3048 -0.2032)
							(mid 0.275042 -0.275042)
							(end 0.2032 -0.3048)
						)
						(arc
							(start -0.2032 -0.3048)
							(mid -0.275042 -0.275042)
							(end -0.3048 -0.2032)
						)
						(arc
							(start -0.3048 0.2032)
							(mid -0.275042 0.275042)
							(end -0.2032 0.3048)
						)
						(arc
							(start 0.2032 0.3048)
							(mid 0.275042 0.275042)
							(end 0.3048 0.2032)
						)
					)
					(width 0)
					(fill yes)
				)
			)
		)
		(pad "2" smd custom
			(at 0 0.4445)
			(size 0.1524 0.1524)
			(layers "F.Cu" "F.Mask" "F.Paste")
			(net "GND")
			(options
				(clearance outline)
				(anchor circle)
			)
			(primitives
				(gr_poly
					(pts
						(arc
							(start 0.3048 -0.2032)
							(mid 0.275042 -0.275042)
							(end 0.2032 -0.3048)
						)
						(arc
							(start -0.2032 -0.3048)
							(mid -0.275042 -0.275042)
							(end -0.3048 -0.2032)
						)
						(arc
							(start -0.3048 0.2032)
							(mid -0.275042 0.275042)
							(end -0.2032 0.3048)
						)
						(arc
							(start 0.2032 0.3048)
							(mid 0.275042 0.275042)
							(end 0.3048 0.2032)
						)
					)
					(width 0)
					(fill yes)
				)
			)
		)
	)
)
